(kicad_pcb
	(version 20260206)
	(generator "pcbnew")
	(generator_version "10.0")
	(general
		(thickness 1.6)
		(legacy_teardrops no)
	)
	(paper "A4")
	(title_block
		(title "12092022_DA0F0TYB4D0_F0T_Panel_BD_Front_D_brd_v02_OCP.brd")
		(comment 1 "Grand Teton / footprints 16-20 of 128")
	)
	(layers
		(0 "F.Cu" signal "TOP")
		(4 "In1.Cu" signal "GND")
		(6 "In2.Cu" signal "GND1")
		(2 "B.Cu" signal "BOTTOM")
		(9 "F.Adhes" user "F.Adhesive")
		(11 "B.Adhes" user "B.Adhesive")
		(13 "F.Paste" user "Package Geometry/Pastemask Top")
		(15 "B.Paste" user "Package Geometry/Pastemask Bottom")
		(5 "F.SilkS" user "Ref Des/Silkscreen Top")
		(7 "B.SilkS" user "Ref Des/Silkscreen Bottom")
		(1 "F.Mask" user "Board Geometry/Soldermask Top")
		(3 "B.Mask" user "Board Geometry/Soldermask Bottom")
		(17 "Dwgs.User" user "User.Drawings")
		(19 "Cmts.User" user "User.Comments")
		(21 "Eco1.User" user "User.Eco1")
		(23 "Eco2.User" user "User.Eco2")
		(25 "Edge.Cuts" user "Board Geometry/Outline")
		(27 "Margin" user)
		(31 "F.CrtYd" user "Package Geometry/Place Bound Top")
		(29 "B.CrtYd" user "Package Geometry/Place Bound Bottom")
		(35 "F.Fab" user "Ref Des/Assembly Top")
		(33 "B.Fab" user "Ref Des/Assembly Bottom")
	)
	(footprint ""
		(layer "F.Cu")
		(at 11.176 -62.738 180)
		(property "Reference" "R13"
			(at -3.302 -0.02667 0)
			(unlocked yes)
			(layer "F.SilkS")
			(effects
				(font
					(size 0.7874 0.5842)
					(thickness 0.1524)
				)
			)
		)
		(property "Value" ""
			(at 0 0 180)
			(layer "F.Fab")
			(effects
				(font
					(size 1.27 1.27)
				)
			)
		)
		(duplicate_pad_numbers_are_jumpers no)
		(fp_line
			(start 0.7874 0.4064)
			(end -0.7874 0.4064)
			(stroke
				(width 0.1524)
				(type default)
			)
			(layer "F.SilkS")
		)
		(fp_line
			(start 0.7874 -0.4064)
			(end 0.7874 0.4064)
			(stroke
				(width 0.1524)
				(type default)
			)
			(layer "F.SilkS")
		)
		(fp_line
			(start -0.7874 0.4064)
			(end -0.7874 -0.4064)
			(stroke
				(width 0.1524)
				(type default)
			)
			(layer "F.SilkS")
		)
		(fp_line
			(start -0.7874 -0.4064)
			(end 0.7874 -0.4064)
			(stroke
				(width 0.1524)
				(type default)
			)
			(layer "F.SilkS")
		)
		(fp_line
			(start 0.67945 0.3048)
			(end 0.120396 0.3048)
			(stroke
				(width 0.1)
				(type default)
			)
			(layer "F.Fab")
		)
		(fp_line
			(start 0.67945 -0.3048)
			(end 0.67945 0.3048)
			(stroke
				(width 0.1)
				(type default)
			)
			(layer "F.Fab")
		)
		(fp_line
			(start 0.12065 -0.2794)
			(end 0.12065 -0.3048)
			(stroke
				(width 0.1)
				(type default)
			)
			(layer "F.Fab")
		)
		(fp_line
			(start 0.12065 -0.3048)
			(end 0.67945 -0.3048)
			(stroke
				(width 0.1)
				(type default)
			)
			(layer "F.Fab")
		)
		(fp_line
			(start 0.120396 0.3048)
			(end 0.120396 0.2794)
			(stroke
				(width 0.1)
				(type default)
			)
			(layer "F.Fab")
		)
		(fp_line
			(start 0.120396 0.2794)
			(end -0.12065 0.2794)
			(stroke
				(width 0.1)
				(type default)
			)
			(layer "F.Fab")
		)
		(fp_line
			(start -0.12065 0.3048)
			(end -0.67945 0.3048)
			(stroke
				(width 0.1)
				(type default)
			)
			(layer "F.Fab")
		)
		(fp_line
			(start -0.12065 0.2794)
			(end -0.12065 0.3048)
			(stroke
				(width 0.1)
				(type default)
			)
			(layer "F.Fab")
		)
		(fp_line
			(start -0.12065 -0.2794)
			(end 0.12065 -0.2794)
			(stroke
				(width 0.1)
				(type default)
			)
			(layer "F.Fab")
		)
		(fp_line
			(start -0.12065 -0.305054)
			(end -0.12065 -0.2794)
			(stroke
				(width 0.1)
				(type default)
			)
			(layer "F.Fab")
		)
		(fp_line
			(start -0.67945 0.3048)
			(end -0.67945 -0.305054)
			(stroke
				(width 0.1)
				(type default)
			)
			(layer "F.Fab")
		)
		(fp_line
			(start -0.67945 -0.305054)
			(end -0.12065 -0.305054)
			(stroke
				(width 0.1)
				(type default)
			)
			(layer "F.Fab")
		)
		(pad "1" smd circle
			(at -0.40005 0 180)
			(size 0 0)
			(layers "F.Cu" "F.Mask" "F.Paste")
			(net "RST_SMB_N")
		)
		(pad "2" smd circle
			(at 0.40005 0 180)
			(size 0 0)
			(layers "F.Cu" "F.Mask" "F.Paste")
			(net "RST_SMB_R_N")
		)
	)
	(footprint ""
		(layer "F.Cu")
		(at 87.757 -155.194 -90)
		(property "Reference" "J6"
			(at -4.28371 0.5969 0)
			(unlocked yes)
			(layer "F.SilkS")
			(effects
				(font
					(size 0.7874 0.5842)
					(thickness 0.1524)
				)
				(justify left)
			)
		)
		(property "Value" ""
			(at 0 0 270)
			(layer "F.Fab")
			(effects
				(font
					(size 1.27 1.27)
				)
			)
		)
		(duplicate_pad_numbers_are_jumpers no)
		(fp_line
			(start -1.2192 2.1082)
			(end -1.2192 -2.1082)
			(stroke
				(width 0.1524)
				(type default)
			)
			(layer "F.SilkS")
		)
		(fp_line
			(start 1.2192 2.1082)
			(end -1.2192 2.1082)
			(stroke
				(width 0.1524)
				(type default)
			)
			(layer "F.SilkS")
		)
		(fp_line
			(start -1.2192 -2.1082)
			(end 1.2192 -2.1082)
			(stroke
				(width 0.1524)
				(type default)
			)
			(layer "F.SilkS")
		)
		(fp_line
			(start 1.2192 -2.1082)
			(end 1.2192 2.1082)
			(stroke
				(width 0.1524)
				(type default)
			)
			(layer "F.SilkS")
		)
		(pad "" np_thru_hole circle
			(at -2.8829 -1.27 180)
			(size 1.0414 1.0414)
			(drill 1.0414)
			(layers "*.Cu" "*.Mask")
			(clearance 0.381)
			(thermal_gap 0.381)
		)
		(pad "" np_thru_hole circle
			(at -2.8829 1.27 180)
			(size 1.0414 1.0414)
			(drill 1.0414)
			(layers "*.Cu" "*.Mask")
			(clearance 0.381)
			(thermal_gap 0.381)
		)
		(pad "" np_thru_hole circle
			(at 3.4671 -1.27 180)
			(size 1.0414 1.0414)
			(drill 1.0414)
			(layers "*.Cu" "*.Mask")
			(clearance 0.381)
			(thermal_gap 0.381)
		)
		(pad "" np_thru_hole circle
			(at 3.4671 1.27 180)
			(size 1.0414 1.0414)
			(drill 1.0414)
			(layers "*.Cu" "*.Mask")
			(clearance 0.381)
			(thermal_gap 0.381)
		)
		(pad "1" smd rect
			(at 0.8255 -0.249936 180)
			(size 0.3048 0.508)
			(layers "F.Cu" "F.Mask" "F.Paste")
			(net "DELTA_L_85_5INCH_TOP_DP")
		)
		(pad "2" smd rect
			(at 0.8255 0.249936 180)
			(size 0.3048 0.508)
			(layers "F.Cu" "F.Mask" "F.Paste")
			(net "DELTA_L_85_5INCH_TOP_DN")
		)
		(pad "3" smd circle
			(at 0 0 270)
			(size 0 0)
			(layers "F.Cu" "F.Mask" "F.Paste")
			(net "GND1")
		)
		(zone
			(layer "F.Cu")
			(hatch none 0.5)
			(connect_pads
				(clearance 0)
			)
			(min_thickness 0.25)
			(keepout
				(tracks not_allowed)
				(vias allowed)
				(pads allowed)
				(copperpour not_allowed)
				(footprints allowed)
			)
			(placement
				(enabled no)
				(sheetname "")
			)
			(fill
				(thermal_gap 0.5)
				(thermal_bridge_width 0.5)
				(island_removal_mode 0)
			)
			(polygon
				(pts
					(xy 88.30564 -154.0764) (xy 88.210136 -154.0764) (xy 88.210136 -154.6733) (xy 87.803736 -154.6733)
					(xy 87.803736 -154.0764) (xy 87.710264 -154.0764) (xy 87.710264 -154.6733) (xy 87.303864 -154.6733)
					(xy 87.303864 -154.0764) (xy 87.20836 -154.0764) (xy 87.20836 -154.7749) (xy 88.30564 -154.7749)
				)
			)
		)
		(zone
			(layers "F.Cu" "B.Cu" "In1.Cu" "In2.Cu")
			(hatch none 0.5)
			(connect_pads
				(clearance 0)
			)
			(min_thickness 0.25)
			(keepout
				(tracks not_allowed)
				(vias allowed)
				(pads allowed)
				(copperpour not_allowed)
				(footprints allowed)
			)
			(placement
				(enabled no)
				(sheetname "")
			)
			(fill
				(thermal_gap 0.5)
				(thermal_bridge_width 0.5)
				(island_removal_mode 0)
			)
			(polygon
				(pts
					(arc
						(start 87.4141 -158.0769)
						(mid 85.5599 -158.0769)
						(end 87.4141 -158.0769)
					)
				)
			)
		)
		(zone
			(layers "F.Cu" "B.Cu" "In1.Cu" "In2.Cu")
			(hatch none 0.5)
			(connect_pads
				(clearance 0)
			)
			(min_thickness 0.25)
			(keepout
				(tracks not_allowed)
				(vias allowed)
				(pads allowed)
				(copperpour not_allowed)
				(footprints allowed)
			)
			(placement
				(enabled no)
				(sheetname "")
			)
			(fill
				(thermal_gap 0.5)
				(thermal_bridge_width 0.5)
				(island_removal_mode 0)
			)
			(polygon
				(pts
					(arc
						(start 87.4141 -151.7269)
						(mid 85.5599 -151.7269)
						(end 87.4141 -151.7269)
					)
				)
			)
		)
		(zone
			(layers "F.Cu" "B.Cu" "In1.Cu" "In2.Cu")
			(hatch none 0.5)
			(connect_pads
				(clearance 0)
			)
			(min_thickness 0.25)
			(keepout
				(tracks not_allowed)
				(vias allowed)
				(pads allowed)
				(copperpour not_allowed)
				(footprints allowed)
			)
			(placement
				(enabled no)
				(sheetname "")
			)
			(fill
				(thermal_gap 0.5)
				(thermal_bridge_width 0.5)
				(island_removal_mode 0)
			)
			(polygon
				(pts
					(arc
						(start 89.9541 -158.0769)
						(mid 88.0999 -158.0769)
						(end 89.9541 -158.0769)
					)
				)
			)
		)
		(zone
			(layers "F.Cu" "B.Cu" "In1.Cu" "In2.Cu")
			(hatch none 0.5)
			(connect_pads
				(clearance 0)
			)
			(min_thickness 0.25)
			(keepout
				(tracks not_allowed)
				(vias allowed)
				(pads allowed)
				(copperpour not_allowed)
				(footprints allowed)
			)
			(placement
				(enabled no)
				(sheetname "")
			)
			(fill
				(thermal_gap 0.5)
				(thermal_bridge_width 0.5)
				(island_removal_mode 0)
			)
			(polygon
				(pts
					(arc
						(start 89.9541 -151.7269)
						(mid 88.0999 -151.7269)
						(end 89.9541 -151.7269)
					)
				)
			)
		)
	)
	(footprint ""
		(layer "F.Cu")
		(at 10.033 -25.019 180)
		(property "Reference" "R7"
			(at 0.762 -1.29667 0)
			(unlocked yes)
			(layer "F.SilkS")
			(effects
				(font
					(size 0.7874 0.5842)
					(thickness 0.1524)
				)
			)
		)
		(property "Value" ""
			(at 0 0 180)
			(layer "F.Fab")
			(effects
				(font
					(size 1.27 1.27)
				)
			)
		)
		(duplicate_pad_numbers_are_jumpers no)
		(fp_line
			(start 1.2954 0.5842)
			(end -1.2954 0.5842)
			(stroke
				(width 0.1524)
				(type default)
			)
			(layer "F.SilkS")
		)
		(fp_line
			(start 1.2954 -0.5842)
			(end 1.2954 0.5842)
			(stroke
				(width 0.1524)
				(type default)
			)
			(layer "F.SilkS")
		)
		(fp_line
			(start -1.2954 0.5842)
			(end -1.2954 -0.5842)
			(stroke
				(width 0.1524)
				(type default)
			)
			(layer "F.SilkS")
		)
		(fp_line
			(start -1.2954 -0.5842)
			(end 1.2954 -0.5842)
			(stroke
				(width 0.1524)
				(type default)
			)
			(layer "F.SilkS")
		)
		(fp_line
			(start 1.1938 0.4064)
			(end 0.8636 0.4064)
			(stroke
				(width 0.1)
				(type default)
			)
			(layer "F.Fab")
		)
		(fp_line
			(start 1.1938 -0.406654)
			(end 1.1938 0.4064)
			(stroke
				(width 0.1)
				(type default)
			)
			(layer "F.Fab")
		)
		(fp_line
			(start 0.8636 0.4572)
			(end -0.8636 0.4572)
			(stroke
				(width 0.1)
				(type default)
			)
			(layer "F.Fab")
		)
		(fp_line
			(start 0.8636 0.4064)
			(end 0.8636 0.4572)
			(stroke
				(width 0.1)
				(type default)
			)
			(layer "F.Fab")
		)
		(fp_line
			(start 0.8636 -0.406654)
			(end 1.1938 -0.406654)
			(stroke
				(width 0.1)
				(type default)
			)
			(layer "F.Fab")
		)
		(fp_line
			(start 0.8636 -0.4572)
			(end 0.8636 -0.406654)
			(stroke
				(width 0.1)
				(type default)
			)
			(layer "F.Fab")
		)
		(fp_line
			(start -0.8636 0.4572)
			(end -0.8636 0.4318)
			(stroke
				(width 0.1)
				(type default)
			)
			(layer "F.Fab")
		)
		(fp_line
			(start -0.8636 0.4318)
			(end -0.8636 0.4064)
			(stroke
				(width 0.1)
				(type default)
			)
			(layer "F.Fab")
		)
		(fp_line
			(start -0.8636 0.4064)
			(end -1.1938 0.4064)
			(stroke
				(width 0.1)
				(type default)
			)
			(layer "F.Fab")
		)
		(fp_line
			(start -0.8636 -0.406654)
			(end -0.8636 -0.4572)
			(stroke
				(width 0.1)
				(type default)
			)
			(layer "F.Fab")
		)
		(fp_line
			(start -0.8636 -0.4572)
			(end 0.8636 -0.4572)
			(stroke
				(width 0.1)
				(type default)
			)
			(layer "F.Fab")
		)
		(fp_line
			(start -1.1938 0.4064)
			(end -1.1938 -0.406654)
			(stroke
				(width 0.1)
				(type default)
			)
			(layer "F.Fab")
		)
		(fp_line
			(start -1.1938 -0.406654)
			(end -0.8636 -0.406654)
			(stroke
				(width 0.1)
				(type default)
			)
			(layer "F.Fab")
		)
		(pad "1" smd rect
			(at -0.7366 0 90)
			(size 0.7112 0.8128)
			(layers "F.Cu" "F.Mask" "F.Paste")
			(net "SYSTEM_FAULT_ID_LED_R2_N")
		)
		(pad "2" smd rect
			(at 0.7366 0 90)
			(size 0.7112 0.8128)
			(layers "F.Cu" "F.Mask" "F.Paste")
			(net "SYSTEM_FAULT_ID_LED_R1_N")
		)
	)
	(footprint ""
		(layer "F.Cu")
		(at 16.891 -9.4234)
		(property "Reference" "R1"
			(at -2.032 -0.07493 0)
			(unlocked yes)
			(layer "F.SilkS")
			(effects
				(font
					(size 0.7874 0.5842)
					(thickness 0.1524)
				)
			)
		)
		(property "Value" ""
			(at 0 0 0)
			(layer "F.Fab")
			(effects
				(font
					(size 1.27 1.27)
				)
			)
		)
		(duplicate_pad_numbers_are_jumpers no)
		(fp_line
			(start -1.2954 -0.5842)
			(end 1.2954 -0.5842)
			(stroke
				(width 0.1524)
				(type default)
			)
			(layer "F.SilkS")
		)
		(fp_line
			(start -1.2954 0.5842)
			(end -1.2954 -0.5842)
			(stroke
				(width 0.1524)
				(type default)
			)
			(layer "F.SilkS")
		)
		(fp_line
			(start 1.2954 -0.5842)
			(end 1.2954 0.5842)
			(stroke
				(width 0.1524)
				(type default)
			)
			(layer "F.SilkS")
		)
		(fp_line
			(start 1.2954 0.5842)
			(end -1.2954 0.5842)
			(stroke
				(width 0.1524)
				(type default)
			)
			(layer "F.SilkS")
		)
		(fp_line
			(start -1.1938 -0.406654)
			(end -0.8636 -0.406654)
			(stroke
				(width 0.1)
				(type default)
			)
			(layer "F.Fab")
		)
		(fp_line
			(start -1.1938 0.4064)
			(end -1.1938 -0.406654)
			(stroke
				(width 0.1)
				(type default)
			)
			(layer "F.Fab")
		)
		(fp_line
			(start -0.8636 -0.4572)
			(end 0.8636 -0.4572)
			(stroke
				(width 0.1)
				(type default)
			)
			(layer "F.Fab")
		)
		(fp_line
			(start -0.8636 -0.406654)
			(end -0.8636 -0.4572)
			(stroke
				(width 0.1)
				(type default)
			)
			(layer "F.Fab")
		)
		(fp_line
			(start -0.8636 0.4064)
			(end -1.1938 0.4064)
			(stroke
				(width 0.1)
				(type default)
			)
			(layer "F.Fab")
		)
		(fp_line
			(start -0.8636 0.4318)
			(end -0.8636 0.4064)
			(stroke
				(width 0.1)
				(type default)
			)
			(layer "F.Fab")
		)
		(fp_line
			(start -0.8636 0.4572)
			(end -0.8636 0.4318)
			(stroke
				(width 0.1)
				(type default)
			)
			(layer "F.Fab")
		)
		(fp_line
			(start 0.8636 -0.4572)
			(end 0.8636 -0.406654)
			(stroke
				(width 0.1)
				(type default)
			)
			(layer "F.Fab")
		)
		(fp_line
			(start 0.8636 -0.406654)
			(end 1.1938 -0.406654)
			(stroke
				(width 0.1)
				(type default)
			)
			(layer "F.Fab")
		)
		(fp_line
			(start 0.8636 0.4064)
			(end 0.8636 0.4572)
			(stroke
				(width 0.1)
				(type default)
			)
			(layer "F.Fab")
		)
		(fp_line
			(start 0.8636 0.4572)
			(end -0.8636 0.4572)
			(stroke
				(width 0.1)
				(type default)
			)
			(layer "F.Fab")
		)
		(fp_line
			(start 1.1938 -0.406654)
			(end 1.1938 0.4064)
			(stroke
				(width 0.1)
				(type default)
			)
			(layer "F.Fab")
		)
		(fp_line
			(start 1.1938 0.4064)
			(end 0.8636 0.4064)
			(stroke
				(width 0.1)
				(type default)
			)
			(layer "F.Fab")
		)
		(pad "1" smd rect
			(at -0.7366 0 270)
			(size 0.7112 0.8128)
			(layers "F.Cu" "F.Mask" "F.Paste")
			(net "P5V_STBY")
		)
		(pad "2" smd rect
			(at 0.7366 0 270)
			(size 0.7112 0.8128)
			(layers "F.Cu" "F.Mask" "F.Paste")
			(net "FM_PFR_LED_AMBER_R")
		)
	)
	(footprint ""
		(layer "F.Cu")
		(at 87.757 -109.601 90)
		(property "Reference" "J5"
			(at -4.46405 -0.74168 0)
			(unlocked yes)
			(layer "F.SilkS")
			(effects
				(font
					(size 0.7874 0.5842)
					(thickness 0.1524)
				)
				(justify left)
			)
		)
		(property "Value" ""
			(at 0 0 90)
			(layer "F.Fab")
			(effects
				(font
					(size 1.27 1.27)
				)
			)
		)
		(duplicate_pad_numbers_are_jumpers no)
		(fp_line
			(start 1.2192 -2.1082)
			(end 1.2192 2.1082)
			(stroke
				(width 0.1524)
				(type default)
			)
			(layer "F.SilkS")
		)
		(fp_line
			(start -1.2192 -2.1082)
			(end 1.2192 -2.1082)
			(stroke
				(width 0.1524)
				(type default)
			)
			(layer "F.SilkS")
		)
		(fp_line
			(start 1.2192 2.1082)
			(end -1.2192 2.1082)
			(stroke
				(width 0.1524)
				(type default)
			)
			(layer "F.SilkS")
		)
		(fp_line
			(start -1.2192 2.1082)
			(end -1.2192 -2.1082)
			(stroke
				(width 0.1524)
				(type default)
			)
			(layer "F.SilkS")
		)
		(pad "" np_thru_hole circle
			(at -2.8829 -1.27)
			(size 1.0414 1.0414)
			(drill 1.0414)
			(layers "*.Cu" "*.Mask")
			(clearance 0.381)
			(thermal_gap 0.381)
		)
		(pad "" np_thru_hole circle
			(at -2.8829 1.27)
			(size 1.0414 1.0414)
			(drill 1.0414)
			(layers "*.Cu" "*.Mask")
			(clearance 0.381)
			(thermal_gap 0.381)
		)
		(pad "" np_thru_hole circle
			(at 3.4671 -1.27)
			(size 1.0414 1.0414)
			(drill 1.0414)
			(layers "*.Cu" "*.Mask")
			(clearance 0.381)
			(thermal_gap 0.381)
		)
		(pad "" np_thru_hole circle
			(at 3.4671 1.27)
			(size 1.0414 1.0414)
			(drill 1.0414)
			(layers "*.Cu" "*.Mask")
			(clearance 0.381)
			(thermal_gap 0.381)
		)
		(pad "1" smd rect
			(at 0.8255 -0.249936)
			(size 0.3048 0.508)
			(layers "F.Cu" "F.Mask" "F.Paste")
			(net "DELTA_L_85_5INCH_TOP_DN")
		)
		(pad "2" smd rect
			(at 0.8255 0.249936)
			(size 0.3048 0.508)
			(layers "F.Cu" "F.Mask" "F.Paste")
			(net "DELTA_L_85_5INCH_TOP_DP")
		)
		(pad "3" smd circle
			(at 0 0 90)
			(size 0 0)
			(layers "F.Cu" "F.Mask" "F.Paste")
			(net "GND1")
		)
		(zone
			(layer "F.Cu")
			(hatch none 0.5)
			(connect_pads
				(clearance 0)
			)
			(min_thickness 0.25)
			(keepout
				(tracks not_allowed)
				(vias allowed)
				(pads allowed)
				(copperpour not_allowed)
				(footprints allowed)
			)
			(placement
				(enabled no)
				(sheetname "")
			)
			(fill
				(thermal_gap 0.5)
				(thermal_bridge_width 0.5)
				(island_removal_mode 0)
			)
			(polygon
				(pts
					(xy 87.20836 -110.7186) (xy 87.303864 -110.7186) (xy 87.303864 -110.1217) (xy 87.710264 -110.1217)
					(xy 87.710264 -110.7186) (xy 87.803736 -110.7186) (xy 87.803736 -110.1217) (xy 88.210136 -110.1217)
					(xy 88.210136 -110.7186) (xy 88.30564 -110.7186) (xy 88.30564 -110.0201) (xy 87.20836 -110.0201)
				)
			)
		)
		(zone
			(layers "F.Cu" "B.Cu" "In1.Cu" "In2.Cu")
			(hatch none 0.5)
			(connect_pads
				(clearance 0)
			)
			(min_thickness 0.25)
			(keepout
				(tracks not_allowed)
				(vias allowed)
				(pads allowed)
				(copperpour not_allowed)
				(footprints allowed)
			)
			(placement
				(enabled no)
				(sheetname "")
			)
			(fill
				(thermal_gap 0.5)
				(thermal_bridge_width 0.5)
				(island_removal_mode 0)
			)
			(polygon
				(pts
					(arc
						(start 87.4141 -113.0681)
						(mid 85.5599 -113.0681)
						(end 87.4141 -113.0681)
					)
				)
			)
		)
		(zone
			(layers "F.Cu" "B.Cu" "In1.Cu" "In2.Cu")
			(hatch none 0.5)
			(connect_pads
				(clearance 0)
			)
			(min_thickness 0.25)
			(keepout
				(tracks not_allowed)
				(vias allowed)
				(pads allowed)
				(copperpour not_allowed)
				(footprints allowed)
			)
			(placement
				(enabled no)
				(sheetname "")
			)
			(fill
				(thermal_gap 0.5)
				(thermal_bridge_width 0.5)
				(island_removal_mode 0)
			)
			(polygon
				(pts
					(arc
						(start 87.4141 -106.7181)
						(mid 85.5599 -106.7181)
						(end 87.4141 -106.7181)
					)
				)
			)
		)
		(zone
			(layers "F.Cu" "B.Cu" "In1.Cu" "In2.Cu")
			(hatch none 0.5)
			(connect_pads
				(clearance 0)
			)
			(min_thickness 0.25)
			(keepout
				(tracks not_allowed)
				(vias allowed)
				(pads allowed)
				(copperpour not_allowed)
				(footprints allowed)
			)
			(placement
				(enabled no)
				(sheetname "")
			)
			(fill
				(thermal_gap 0.5)
				(thermal_bridge_width 0.5)
				(island_removal_mode 0)
			)
			(polygon
				(pts
					(arc
						(start 89.9541 -113.0681)
						(mid 88.0999 -113.0681)
						(end 89.9541 -113.0681)
					)
				)
			)
		)
		(zone
			(layers "F.Cu" "B.Cu" "In1.Cu" "In2.Cu")
			(hatch none 0.5)
			(connect_pads
				(clearance 0)
			)
			(min_thickness 0.25)
			(keepout
				(tracks not_allowed)
				(vias allowed)
				(pads allowed)
				(copperpour not_allowed)
				(footprints allowed)
			)
			(placement
				(enabled no)
				(sheetname "")
			)
			(fill
				(thermal_gap 0.5)
				(thermal_bridge_width 0.5)
				(island_removal_mode 0)
			)
			(polygon
				(pts
					(arc
						(start 89.9541 -106.7181)
						(mid 88.0999 -106.7181)
						(end 89.9541 -106.7181)
					)
				)
			)
		)
	)
)
